(kicad_pcb
	(version 20260206)
	(generator "pcbnew")
	(generator_version "10.0")
	(general
		(thickness 1.6)
		(legacy_teardrops no)
	)
	(paper "A4")
	(title_block
		(title "Bryce Canyon_SCC_16316-1_OCP.brd")
		(comment 1 "Bryce Canyon / footprints 682-688 of 1561")
	)
	(layers
		(0 "F.Cu" signal "TOP")
		(4 "In1.Cu" signal "L2GND")
		(6 "In2.Cu" signal "L3")
		(8 "In3.Cu" signal "L4VCC")
		(10 "In4.Cu" signal "L5VCC")
		(12 "In5.Cu" signal "L6")
		(14 "In6.Cu" signal "L7GND")
		(2 "B.Cu" signal "BOTTOM")
		(9 "F.Adhes" user "F.Adhesive")
		(11 "B.Adhes" user "B.Adhesive")
		(13 "F.Paste" user "Package Geometry/Pastemask Top")
		(15 "B.Paste" user "Package Geometry/Pastemask Bottom")
		(5 "F.SilkS" user "Ref Des/Silkscreen Top")
		(7 "B.SilkS" user "Ref Des/Silkscreen Bottom")
		(1 "F.Mask" user "Board Geometry/Soldermask Top")
		(3 "B.Mask" user "Board Geometry/Soldermask Bottom")
		(17 "Dwgs.User" user "User.Drawings")
		(19 "Cmts.User" user "User.Comments")
		(21 "Eco1.User" user "User.Eco1")
		(23 "Eco2.User" user "User.Eco2")
		(25 "Edge.Cuts" user "Board Geometry/Outline")
		(27 "Margin" user)
		(31 "F.CrtYd" user "Package Geometry/Place Bound Top")
		(29 "B.CrtYd" user "Package Geometry/Place Bound Bottom")
		(35 "F.Fab" user "Ref Des/Assembly Top")
		(33 "B.Fab" user "Ref Des/Assembly Bottom")
	)
	(footprint ""
		(layer "F.Cu")
		(at 167.34536 -100.67544)
		(property "Reference" "R535"
			(at 0 0 0)
			(layer "F.SilkS")
			(hide yes)
			(effects
				(font
					(size 1.27 1.27)
				)
			)
		)
		(property "Value" "0R2J-2-GP"
			(at 0.064008 -3.993896 0)
			(unlocked yes)
			(layer "F.Fab")
			(hide yes)
			(effects
				(font
					(size 1.016 1.016)
					(thickness 0.1524)
				)
			)
		)
		(property "Device Type" "R402H16"
			(at 0.064008 -5.517896 0)
			(unlocked yes)
			(layer "F.Fab")
			(hide yes)
			(effects
				(font
					(size 1.016 1.016)
					(thickness 0.1524)
				)
			)
		)
		(duplicate_pad_numbers_are_jumpers no)
		(fp_line
			(start -0.508 -0.9398)
			(end -0.508 0.9398)
			(stroke
				(width 0.1524)
				(type default)
			)
			(layer "F.SilkS")
		)
		(fp_line
			(start 0.508 -0.9398)
			(end -0.508 -0.9398)
			(stroke
				(width 0.1524)
				(type default)
			)
			(layer "F.SilkS")
		)
		(fp_rect
			(start -0.508 0.9398)
			(end 0.508 -0.9398)
			(stroke
				(width 0)
				(type default)
			)
			(fill no)
			(layer "F.CrtYd")
		)
		(fp_rect
			(start -0.508 0.9398)
			(end 0.508 -0.9398)
			(stroke
				(width 0)
				(type default)
			)
			(fill no)
			(layer "F.Fab")
		)
		(pad "1" smd custom
			(at 0 -0.4445)
			(size 0.1397 0.1397)
			(layers "F.Cu" "F.Mask" "F.Paste")
			(net "SCC_FULL_PGOOD")
			(options
				(clearance outline)
				(anchor circle)
			)
			(primitives
				(gr_poly
					(pts
						(arc
							(start -0.1778 -0.2794)
							(mid -0.249642 -0.249642)
							(end -0.2794 -0.1778)
						)
						(arc
							(start -0.2794 0.1778)
							(mid -0.249642 0.249642)
							(end -0.1778 0.2794)
						)
						(arc
							(start 0.1778 0.2794)
							(mid 0.249642 0.249642)
							(end 0.2794 0.1778)
						)
						(arc
							(start 0.2794 -0.1778)
							(mid 0.249642 -0.249642)
							(end 0.1778 -0.2794)
						)
					)
					(width 0)
					(fill yes)
				)
			)
		)
		(pad "2" smd custom
			(at 0 0.4445)
			(size 0.1397 0.1397)
			(layers "F.Cu" "F.Mask" "F.Paste")
			(net "P0V975_STAT")
			(options
				(clearance outline)
				(anchor circle)
			)
			(primitives
				(gr_poly
					(pts
						(arc
							(start -0.1778 -0.2794)
							(mid -0.249642 -0.249642)
							(end -0.2794 -0.1778)
						)
						(arc
							(start -0.2794 0.1778)
							(mid -0.249642 0.249642)
							(end -0.1778 0.2794)
						)
						(arc
							(start 0.1778 0.2794)
							(mid 0.249642 0.249642)
							(end 0.2794 0.1778)
						)
						(arc
							(start 0.2794 -0.1778)
							(mid 0.249642 -0.249642)
							(end 0.1778 -0.2794)
						)
					)
					(width 0)
					(fill yes)
				)
			)
		)
	)
	(footprint ""
		(layer "F.Cu")
		(at 160.274 -70.80123 -90)
		(property "Reference" "R359"
			(at 0 0 270)
			(layer "F.SilkS")
			(hide yes)
			(effects
				(font
					(size 1.27 1.27)
				)
			)
		)
		(property "Value" "1KR2F-3-GP"
			(at 0.064008 -3.993896 270)
			(unlocked yes)
			(layer "F.Fab")
			(hide yes)
			(effects
				(font
					(size 1.016 1.016)
					(thickness 0.1524)
				)
			)
		)
		(property "Device Type" "R402H16"
			(at 0.064008 -5.517896 270)
			(unlocked yes)
			(layer "F.Fab")
			(hide yes)
			(effects
				(font
					(size 1.016 1.016)
					(thickness 0.1524)
				)
			)
		)
		(duplicate_pad_numbers_are_jumpers no)
		(fp_line
			(start -0.508 -0.9398)
			(end -0.508 0.9398)
			(stroke
				(width 0.1524)
				(type default)
			)
			(layer "F.SilkS")
		)
		(fp_line
			(start 0.508 -0.9398)
			(end -0.508 -0.9398)
			(stroke
				(width 0.1524)
				(type default)
			)
			(layer "F.SilkS")
		)
		(fp_rect
			(start -0.508 0.9398)
			(end 0.508 -0.9398)
			(stroke
				(width 0)
				(type default)
			)
			(fill no)
			(layer "F.CrtYd")
		)
		(fp_rect
			(start -0.508 0.9398)
			(end 0.508 -0.9398)
			(stroke
				(width 0)
				(type default)
			)
			(fill no)
			(layer "F.Fab")
		)
		(pad "1" smd custom
			(at 0 -0.4445 270)
			(size 0.1397 0.1397)
			(layers "F.Cu" "F.Mask" "F.Paste")
			(net "P0V975")
			(options
				(clearance outline)
				(anchor circle)
			)
			(primitives
				(gr_poly
					(pts
						(arc
							(start -0.1778 -0.2794)
							(mid -0.249642 -0.249642)
							(end -0.2794 -0.1778)
						)
						(arc
							(start -0.2794 0.1778)
							(mid -0.249642 0.249642)
							(end -0.1778 0.2794)
						)
						(arc
							(start 0.1778 0.2794)
							(mid 0.249642 0.249642)
							(end 0.2794 0.1778)
						)
						(arc
							(start 0.2794 -0.1778)
							(mid 0.249642 -0.249642)
							(end 0.1778 -0.2794)
						)
					)
					(width 0)
					(fill yes)
				)
			)
		)
		(pad "2" smd custom
			(at 0 0.4445 270)
			(size 0.1397 0.1397)
			(layers "F.Cu" "F.Mask" "F.Paste")
			(net "P0V975_SENSE")
			(options
				(clearance outline)
				(anchor circle)
			)
			(primitives
				(gr_poly
					(pts
						(arc
							(start -0.1778 -0.2794)
							(mid -0.249642 -0.249642)
							(end -0.2794 -0.1778)
						)
						(arc
							(start -0.2794 0.1778)
							(mid -0.249642 0.249642)
							(end -0.1778 0.2794)
						)
						(arc
							(start 0.1778 0.2794)
							(mid 0.249642 0.249642)
							(end 0.2794 0.1778)
						)
						(arc
							(start 0.2794 -0.1778)
							(mid 0.249642 -0.249642)
							(end 0.1778 -0.2794)
						)
					)
					(width 0)
					(fill yes)
				)
			)
		)
	)
	(footprint ""
		(layer "F.Cu")
		(at 185.478674 -24.966422 -90)
		(property "Reference" "R235"
			(at 0 0 270)
			(layer "F.SilkS")
			(hide yes)
			(effects
				(font
					(size 1.27 1.27)
				)
			)
		)
		(property "Value" "4K7R2F-GP"
			(at 0.064008 -3.993896 270)
			(unlocked yes)
			(layer "F.Fab")
			(hide yes)
			(effects
				(font
					(size 1.016 1.016)
					(thickness 0.1524)
				)
			)
		)
		(property "Device Type" "R402H16"
			(at 0.064008 -5.517896 270)
			(unlocked yes)
			(layer "F.Fab")
			(hide yes)
			(effects
				(font
					(size 1.016 1.016)
					(thickness 0.1524)
				)
			)
		)
		(duplicate_pad_numbers_are_jumpers no)
		(fp_line
			(start -0.508 -0.9398)
			(end -0.508 0.9398)
			(stroke
				(width 0.1524)
				(type default)
			)
			(layer "F.SilkS")
		)
		(fp_line
			(start 0.508 -0.9398)
			(end -0.508 -0.9398)
			(stroke
				(width 0.1524)
				(type default)
			)
			(layer "F.SilkS")
		)
		(fp_rect
			(start -0.508 0.9398)
			(end 0.508 -0.9398)
			(stroke
				(width 0)
				(type default)
			)
			(fill no)
			(layer "F.CrtYd")
		)
		(fp_rect
			(start -0.508 0.9398)
			(end 0.508 -0.9398)
			(stroke
				(width 0)
				(type default)
			)
			(fill no)
			(layer "F.Fab")
		)
		(pad "1" smd custom
			(at 0 -0.4445 270)
			(size 0.1397 0.1397)
			(layers "F.Cu" "F.Mask" "F.Paste")
			(net "P1V8_C")
			(options
				(clearance outline)
				(anchor circle)
			)
			(primitives
				(gr_poly
					(pts
						(arc
							(start -0.1778 -0.2794)
							(mid -0.249642 -0.249642)
							(end -0.2794 -0.1778)
						)
						(arc
							(start -0.2794 0.1778)
							(mid -0.249642 0.249642)
							(end -0.1778 0.2794)
						)
						(arc
							(start 0.1778 0.2794)
							(mid 0.249642 0.249642)
							(end 0.2794 0.1778)
						)
						(arc
							(start 0.2794 -0.1778)
							(mid 0.249642 -0.249642)
							(end 0.1778 -0.2794)
						)
					)
					(width 0)
					(fill yes)
				)
			)
		)
		(pad "2" smd custom
			(at 0 0.4445 270)
			(size 0.1397 0.1397)
			(layers "F.Cu" "F.Mask" "F.Paste")
			(net "IOC_UART_0_RX")
			(options
				(clearance outline)
				(anchor circle)
			)
			(primitives
				(gr_poly
					(pts
						(arc
							(start -0.1778 -0.2794)
							(mid -0.249642 -0.249642)
							(end -0.2794 -0.1778)
						)
						(arc
							(start -0.2794 0.1778)
							(mid -0.249642 0.249642)
							(end -0.1778 0.2794)
						)
						(arc
							(start 0.1778 0.2794)
							(mid 0.249642 0.249642)
							(end 0.2794 0.1778)
						)
						(arc
							(start 0.2794 -0.1778)
							(mid 0.249642 -0.249642)
							(end 0.1778 -0.2794)
						)
					)
					(width 0)
					(fill yes)
				)
			)
		)
	)
	(footprint ""
		(layer "F.Cu")
		(at 13.53947 -89.003378)
		(property "Reference" "U40"
			(at 0 0 0)
			(layer "F.SilkS")
			(hide yes)
			(effects
				(font
					(size 1.27 1.27)
				)
			)
		)
		(property "Value" "PCA9306DCTR-GP"
			(at 0 -11.6332 0)
			(unlocked yes)
			(layer "F.Fab")
			(hide yes)
			(effects
				(font
					(size 1.016 1.016)
					(thickness 0.1524)
				)
			)
		)
		(property "Device Type" "SSOIC8H52"
			(at 0 -13.1572 0)
			(unlocked yes)
			(layer "F.Fab")
			(hide yes)
			(effects
				(font
					(size 1.016 1.016)
					(thickness 0.1524)
				)
			)
		)
		(duplicate_pad_numbers_are_jumpers no)
		(fp_line
			(start -1.7018 -0.5842)
			(end -1.7018 2.286)
			(stroke
				(width 0.1524)
				(type default)
			)
			(layer "F.SilkS")
		)
		(fp_line
			(start -1.7018 -0.5842)
			(end 1.0668 -0.5842)
			(stroke
				(width 0.1524)
				(type default)
			)
			(layer "F.SilkS")
		)
		(fp_line
			(start -1.524 0.5842)
			(end -1.524 2.286)
			(stroke
				(width 0.508)
				(type default)
			)
			(layer "F.SilkS")
		)
		(fp_line
			(start -1.397 0)
			(end -1.7018 -0.3048)
			(stroke
				(width 0.1524)
				(type default)
			)
			(layer "F.SilkS")
		)
		(fp_line
			(start -1.397 0)
			(end -1.7018 0.3048)
			(stroke
				(width 0.1524)
				(type default)
			)
			(layer "F.SilkS")
		)
		(fp_line
			(start 1.0668 -0.5842)
			(end 1.0668 0.5842)
			(stroke
				(width 0.1524)
				(type default)
			)
			(layer "F.SilkS")
		)
		(fp_line
			(start 1.0668 0.5842)
			(end -1.524 0.5842)
			(stroke
				(width 0.1524)
				(type default)
			)
			(layer "F.SilkS")
		)
		(fp_poly
			(pts
				(xy -1.1684 -0.5842) (xy 1.0668 -0.5842) (xy 1.0668 0.5842) (xy -1.1684 0.5842)
			)
			(stroke
				(width 0)
				(type default)
			)
			(fill yes)
			(layer "F.SilkS")
		)
		(fp_poly
			(pts
				(xy -1.778 2.54) (xy 1.778 2.54) (xy 1.778 -2.54) (xy -1.778 -2.54)
			)
			(stroke
				(width 0)
				(type default)
			)
			(fill no)
			(layer "F.CrtYd")
		)
		(fp_poly
			(pts
				(xy -1.778 -2.54) (xy 1.778 -2.54) (xy 1.778 2.54) (xy -1.778 2.54)
			)
			(stroke
				(width 0)
				(type default)
			)
			(fill no)
			(layer "F.Fab")
		)
		(pad "1" smd rect
			(at -0.97536 1.6256)
			(size 0.3556 1.524)
			(layers "F.Cu" "F.Mask" "F.Paste")
			(net "GND")
		)
		(pad "2" smd rect
			(at -0.32512 1.6256)
			(size 0.3556 1.524)
			(layers "F.Cu" "F.Mask" "F.Paste")
			(net "P1V8_E")
		)
		(pad "3" smd rect
			(at 0.32512 1.6256)
			(size 0.3556 1.524)
			(layers "F.Cu" "F.Mask" "F.Paste")
			(net "I2C_DPB_SCL3_LS")
		)
		(pad "4" smd rect
			(at 0.97536 1.6256)
			(size 0.3556 1.524)
			(layers "F.Cu" "F.Mask" "F.Paste")
			(net "I2C_DPB_SDA3_LS")
		)
		(pad "5" smd rect
			(at 0.97536 -1.6256)
			(size 0.3556 1.524)
			(layers "F.Cu" "F.Mask" "F.Paste")
			(net "I2C_DPB_SDA3")
		)
		(pad "6" smd rect
			(at 0.32512 -1.6256)
			(size 0.3556 1.524)
			(layers "F.Cu" "F.Mask" "F.Paste")
			(net "I2C_DPB_SCL3")
		)
		(pad "7" smd rect
			(at -0.32512 -1.6256)
			(size 0.3556 1.524)
			(layers "F.Cu" "F.Mask" "F.Paste")
			(net "VREF3")
		)
		(pad "8" smd rect
			(at -0.97536 -1.6256)
			(size 0.3556 1.524)
			(layers "F.Cu" "F.Mask" "F.Paste")
			(net "LS_EN_U40")
		)
	)
	(footprint ""
		(layer "F.Cu")
		(at 168.42994 -58.08345)
		(property "Reference" "R264"
			(at 0 0 0)
			(layer "F.SilkS")
			(hide yes)
			(effects
				(font
					(size 1.27 1.27)
				)
			)
		)
		(property "Value" "4K7R2F-GP"
			(at 0.064008 -3.993896 0)
			(unlocked yes)
			(layer "F.Fab")
			(hide yes)
			(effects
				(font
					(size 1.016 1.016)
					(thickness 0.1524)
				)
			)
		)
		(property "Device Type" "R402H16"
			(at 0.064008 -5.517896 0)
			(unlocked yes)
			(layer "F.Fab")
			(hide yes)
			(effects
				(font
					(size 1.016 1.016)
					(thickness 0.1524)
				)
			)
		)
		(duplicate_pad_numbers_are_jumpers no)
		(fp_line
			(start -0.508 -0.9398)
			(end -0.508 0.9398)
			(stroke
				(width 0.1524)
				(type default)
			)
			(layer "F.SilkS")
		)
		(fp_line
			(start 0.508 -0.9398)
			(end -0.508 -0.9398)
			(stroke
				(width 0.1524)
				(type default)
			)
			(layer "F.SilkS")
		)
		(fp_rect
			(start -0.508 0.9398)
			(end 0.508 -0.9398)
			(stroke
				(width 0)
				(type default)
			)
			(fill no)
			(layer "F.CrtYd")
		)
		(fp_rect
			(start -0.508 0.9398)
			(end 0.508 -0.9398)
			(stroke
				(width 0)
				(type default)
			)
			(fill no)
			(layer "F.Fab")
		)
		(pad "1" smd custom
			(at 0 -0.4445)
			(size 0.1397 0.1397)
			(layers "F.Cu" "F.Mask" "F.Paste")
			(net "P1V8_C")
			(options
				(clearance outline)
				(anchor circle)
			)
			(primitives
				(gr_poly
					(pts
						(arc
							(start -0.1778 -0.2794)
							(mid -0.249642 -0.249642)
							(end -0.2794 -0.1778)
						)
						(arc
							(start -0.2794 0.1778)
							(mid -0.249642 0.249642)
							(end -0.1778 0.2794)
						)
						(arc
							(start 0.1778 0.2794)
							(mid 0.249642 0.249642)
							(end 0.2794 0.1778)
						)
						(arc
							(start 0.2794 -0.1778)
							(mid 0.249642 -0.249642)
							(end 0.1778 -0.2794)
						)
					)
					(width 0)
					(fill yes)
				)
			)
		)
		(pad "2" smd custom
			(at 0 0.4445)
			(size 0.1397 0.1397)
			(layers "F.Cu" "F.Mask" "F.Paste")
			(net "ICE0_TRST#")
			(options
				(clearance outline)
				(anchor circle)
			)
			(primitives
				(gr_poly
					(pts
						(arc
							(start -0.1778 -0.2794)
							(mid -0.249642 -0.249642)
							(end -0.2794 -0.1778)
						)
						(arc
							(start -0.2794 0.1778)
							(mid -0.249642 0.249642)
							(end -0.1778 0.2794)
						)
						(arc
							(start 0.1778 0.2794)
							(mid 0.249642 0.249642)
							(end 0.2794 0.1778)
						)
						(arc
							(start 0.2794 -0.1778)
							(mid 0.249642 -0.249642)
							(end 0.1778 -0.2794)
						)
					)
					(width 0)
					(fill yes)
				)
			)
		)
	)
	(footprint ""
		(layer "F.Cu")
		(at 55.88 -119.507 -90)
		(property "Reference" "C703"
			(at 0 0 270)
			(layer "F.SilkS")
			(hide yes)
			(effects
				(font
					(size 1.27 1.27)
				)
			)
		)
		(property "Value" "SC10U6D3V5KX-4GP"
			(at -0.0762 -6.1214 270)
			(unlocked yes)
			(layer "F.Fab")
			(hide yes)
			(effects
				(font
					(size 1.016 1.016)
					(thickness 0.1524)
				)
			)
		)
		(property "Device Type" "C805H58"
			(at -0.0762 -8.1534 270)
			(unlocked yes)
			(layer "F.Fab")
			(hide yes)
			(effects
				(font
					(size 1.016 1.016)
					(thickness 0.1524)
				)
			)
		)
		(duplicate_pad_numbers_are_jumpers no)
		(fp_line
			(start 0.635 0)
			(end -0.635 0)
			(stroke
				(width 0.508)
				(type default)
			)
			(layer "F.SilkS")
		)
		(fp_rect
			(start -0.9652 1.778)
			(end 0.9652 -1.778)
			(stroke
				(width 0)
				(type default)
			)
			(fill no)
			(layer "F.CrtYd")
		)
		(fp_poly
			(pts
				(xy -0.9652 -1.778) (xy 0.9652 -1.778) (xy 0.9652 1.778) (xy -0.9652 1.778)
			)
			(stroke
				(width 0)
				(type default)
			)
			(fill no)
			(layer "F.Fab")
		)
		(pad "1" smd rect
			(at 0 -0.9652 270)
			(size 1.397 1.143)
			(layers "F.Cu" "F.Mask" "F.Paste")
			(net "P3V3_OUT")
		)
		(pad "2" smd rect
			(at 0 0.9652 270)
			(size 1.397 1.143)
			(layers "F.Cu" "F.Mask" "F.Paste")
			(net "GND")
		)
	)
	(footprint ""
		(layer "F.Cu")
		(at 7.4422 -43.561 90)
		(property "Reference" "R527"
			(at 0 0 90)
			(layer "F.SilkS")
			(hide yes)
			(effects
				(font
					(size 1.27 1.27)
				)
			)
		)
		(property "Value" "0R5J-5-GP"
			(at 0 -8.9535 90)
			(unlocked yes)
			(layer "F.Fab")
			(hide yes)
			(effects
				(font
					(size 1.27 1.016)
					(thickness 0.1524)
				)
			)
		)
		(property "Device Type" "R805H24"
			(at 0 -10.6299 90)
			(unlocked yes)
			(layer "F.Fab")
			(hide yes)
			(effects
				(font
					(size 1.27 1.016)
					(thickness 0.1524)
				)
			)
		)
		(duplicate_pad_numbers_are_jumpers no)
		(fp_line
			(start 0.889 -1.7018)
			(end -0.889 -1.7018)
			(stroke
				(width 0.1524)
				(type default)
			)
			(layer "F.SilkS")
		)
		(fp_line
			(start 0.889 -1.7018)
			(end 0.889 -0.381)
			(stroke
				(width 0.1524)
				(type default)
			)
			(layer "F.SilkS")
		)
		(fp_line
			(start -0.889 -1.7018)
			(end -0.889 0.2794)
			(stroke
				(width 0.1524)
				(type default)
			)
			(layer "F.SilkS")
		)
		(fp_line
			(start -0.889 0.0762)
			(end -0.889 1.7018)
			(stroke
				(width 0.1524)
				(type default)
			)
			(layer "F.SilkS")
		)
		(fp_line
			(start 0.889 1.7018)
			(end 0.889 -0.508)
			(stroke
				(width 0.1524)
				(type default)
			)
			(layer "F.SilkS")
		)
		(fp_line
			(start -0.889 1.7018)
			(end 0.889 1.7018)
			(stroke
				(width 0.1524)
				(type default)
			)
			(layer "F.SilkS")
		)
		(fp_poly
			(pts
				(xy 0.9652 -1.778) (xy 0.9652 1.778) (xy -0.9652 1.778) (xy -0.9652 -1.778)
			)
			(stroke
				(width 0)
				(type default)
			)
			(fill no)
			(layer "F.CrtYd")
		)
		(fp_rect
			(start -0.9652 1.778)
			(end 0.9652 -1.778)
			(stroke
				(width 0)
				(type default)
			)
			(fill no)
			(layer "F.Fab")
		)
		(pad "1" smd rect
			(at 0 -0.9652 90)
			(size 1.397 1.143)
			(layers "F.Cu" "F.Mask" "F.Paste")
			(net "MB0_CM_GATE")
		)
		(pad "2" smd rect
			(at 0 0.9652 90)
			(size 1.397 1.143)
			(layers "F.Cu" "F.Mask" "F.Paste")
			(net "MB0_CM_GATE_R")
		)
	)
)
